# S9S_MB_2U (Grand Teton) — schematic netlist excerpt (pin names and nets, part order shuffled) for the footprints in the layout excerpt that follows; sources: Cadence DE-HDL packaged netlist, KiCad conversion of 03242023_DA0F0TMBIJ0_F0T_Motherboard_J_brd_V01_OCP.brd

J26  SCONN288_ADR50017P087CC  SCONN288_ADR50017-P087CC IO  pkg DDR288S_1-1VXB  page 107
  VIN_BULK0  = P12V_S3_AUX_CPU1_NVDIMM
  RFU0  = TP_CHE_CPU1_DIMM2_FRU_0
  VIN_MGMT  = P3V3_AUX
  HSCL  = I3C_SPD_DDREFGH_CPU1_LVC1_SCL_1
  HSDA  = I3C_SPD_DDREFGH_CPU1_LVC1_SDA
  VSS0  = GND
  DQ0_A  = M_E_CPU1_SA_DQ<0>
  VSS1  = GND
  DQ1_A  = M_E_CPU1_SA_DQ<1>
  VSS2  = GND
  DQS0_A_T  = M_E_CPU1_SA_DQS_DP<0>
  DQS0_A_C  = M_E_CPU1_SA_DQS_DN<0>
  VSS3  = GND
  DQ4_A  = M_E_CPU1_SA_DQ<4>
  VSS4  = GND
  DQ5_A  = M_E_CPU1_SA_DQ<5>
  VSS5  = GND
  DQ8_A  = M_E_CPU1_SA_DQ<8>
  VSS6  = GND
  DQ9_A  = M_E_CPU1_SA_DQ<9>
  VSS7  = GND
  DQS1_A_T  = M_E_CPU1_SA_DQS_DP<1>
  DQS1_A_C  = M_E_CPU1_SA_DQS_DN<1>
  VSS8  = GND
  DQ12_A  = M_E_CPU1_SA_DQ<12>
  VSS9  = GND
  DQ13_A  = M_E_CPU1_SA_DQ<13>
  VSS10  = GND
  DQ16_A  = M_E_CPU1_SA_DQ<16>
  VSS11  = GND
  DQ17_A  = M_E_CPU1_SA_DQ<17>
  VSS12  = GND
  DQS2_A_T  = M_E_CPU1_SA_DQS_DP<2>
  DQS2_A_C  = M_E_CPU1_SA_DQS_DN<2>
  VSS13  = GND
  DQ20_A  = M_E_CPU1_SA_DQ<20>
  VSS14  = GND
  DQ21_A  = M_E_CPU1_SA_DQ<21>
  VSS15  = GND
  DQ24_A  = M_E_CPU1_SA_DQ<24>
  VSS16  = GND
  DQ25_A  = M_E_CPU1_SA_DQ<25>
  VSS17  = GND
  DQS3_A_T  = M_E_CPU1_SA_DQS_DP<3>
  DQS3_A_C  = M_E_CPU1_SA_DQS_DN<3>
  VSS18  = GND
  DQ28_A  = M_E_CPU1_SA_DQ<28>
  VSS19  = GND
  DQ29_A  = M_E_CPU1_SA_DQ<29>
  VSS20  = GND
  CB0_A  = M_E_CPU1_SA_CB<0>
  VSS21  = GND
  CB1_A  = M_E_CPU1_SA_CB<1>
  VSS22  = GND
  DQS4_A_T  = M_E_CPU1_SA_DQS_DP<4>
  DQS4_A_C  = M_E_CPU1_SA_DQS_DN<4>
  VSS23  = GND
  CB4_A  = M_E_CPU1_SA_CB<4>
  VSS24  = GND
  CB5_A  = M_E_CPU1_SA_CB<5>
  VSS25  = GND
  ALERT_N  = M_E_CPU1_ALERT_N
  VSS26  = GND
  CS0_A_N  = M_E_CPU1_SA_CS_N<2>
  VSS27  = GND
  CA0_A  = M_E_CPU1_SA_CA<0>
  VSS28  = GND
  CA2_A  = M_E_CPU1_SA_CA<2>
  VSS29  = GND
  CA4_A  = M_E_CPU1_SA_CA<4>
  VSS30  = GND
  CA6_A  = M_E_CPU1_SA_CA<6>
  VSS31  = GND
  PAR_A  = M_E_CPU1_SA_PAR
  VSS32  = GND
  CA0_B  = M_E_CPU1_SB_CA<0>
  VSS33  = GND
  CA2_B  = M_E_CPU1_SB_CA<2>
  VSS34  = GND
  CA4_B  = M_E_CPU1_SB_CA<4>
  VSS35  = GND
  CA6_B  = M_E_CPU1_SB_CA<6>
  VSS36  = GND
  CS0_B_N  = M_E_CPU1_SB_CS_N<2>
  VSS37  = GND
  \lbd||rsp_a_n\  = M_E_CPU1_SA_RSP<1>
  \lbs||rsp_b_n\  = M_E_CPU1_SB_RSP<1>
  VSS38  = GND
  CB4_B  = M_E_CPU1_SB_CB<4>
  VSS39  = GND
  CB5_B  = M_E_CPU1_SB_CB<5>
  VSS40  = GND
  \dqs9_b_t||tdqs9_b_t||dbi4_b_n\  = M_E_CPU1_SB_DQS_DP<9>
  \dqs9_b_c||tdqs9_b_c\  = M_E_CPU1_SB_DQS_DN<9>
  VSS41  = GND
  CB0_B  = M_E_CPU1_SB_CB<0>
  VSS42  = GND
  CB1_B  = M_E_CPU1_SB_CB<1>
  VSS43  = GND
  DQ0_B  = M_E_CPU1_SB_DQ<0>
  VSS44  = GND
  DQ1_B  = M_E_CPU1_SB_DQ<1>
  VSS45  = GND
  DQS0_B_T  = M_E_CPU1_SB_DQS_DP<0>
  DQS0_B_C  = M_E_CPU1_SB_DQS_DN<0>
  VSS46  = GND
  DQ4_B  = M_E_CPU1_SB_DQ<4>
  VSS47  = GND
  DQ5_B  = M_E_CPU1_SB_DQ<5>
  VSS48  = GND
  DQ8_B  = M_E_CPU1_SB_DQ<8>
  VSS49  = GND
  DQ9_B  = M_E_CPU1_SB_DQ<9>
  VSS50  = GND
  DQS1_B_T  = M_E_CPU1_SB_DQS_DP<1>
  DQS1_B_C  = M_E_CPU1_SB_DQS_DN<1>
  VSS51  = GND
  DQ12_B  = M_E_CPU1_SB_DQ<12>
  VSS52  = GND
  DQ13_B  = M_E_CPU1_SB_DQ<13>
  VSS53  = GND
  DQ16_B  = M_E_CPU1_SB_DQ<16>
  VSS54  = GND
  DQ17_B  = M_E_CPU1_SB_DQ<17>
  VSS55  = GND
  DQS2_B_T  = M_E_CPU1_SB_DQS_DP<2>
  DQS2_B_C  = M_E_CPU1_SB_DQS_DN<2>
  VSS56  = GND
  DQ20_B  = M_E_CPU1_SB_DQ<20>
  VSS57  = GND
  DQ21_B  = M_E_CPU1_SB_DQ<21>
  VSS58  = GND
  DQ24_B  = M_E_CPU1_SB_DQ<24>
  VSS59  = GND
  DQ25_B  = M_E_CPU1_SB_DQ<25>
  VSS60  = GND
  DQS3_B_T  = M_E_CPU1_SB_DQS_DP<3>
  DQS3_B_C  = M_E_CPU1_SB_DQS_DN<3>
  VSS61  = GND
  DQ28_B  = M_E_CPU1_SB_DQ<28>
  VSS62  = GND
  DQ29_B  = M_E_CPU1_SB_DQ<29>
  VSS63  = GND
  RFU1  = TP_CHE_CPU1_DIMM2_FRU_1
  VIN_BULK1  = P12V_S3_AUX_CPU1_NVDIMM
  VIN_BULK2  = P12V_S3_AUX_CPU1_NVDIMM
  \pwr_good||fail_n\  = PWRGD_CHE_CPU1_DIMM2
  HSA  = PD_CHE_CPU1_DIMM2_SAA
  RFU2  = TP_CHE_CPU1_DIMM2_FRU_2
  RFU3  = TP_CHE_CPU1_DIMM2_FRU_3
  VSS64  = GND
  DQ2_A  = M_E_CPU1_SA_DQ<2>
  VSS65  = GND
  DQ3_A  = M_E_CPU1_SA_DQ<3>
  VSS66  = GND
  \dqs5_a_c||tdqs5_a_c||dqs5_a_t||tdqs5_a_t\  = M_E_CPU1_SA_DQS_DN<5>
  \dqs5_a_t||tdqs5_a_t\  = M_E_CPU1_SA_DQS_DP<5>
  VSS67  = GND
  DQ6_A  = M_E_CPU1_SA_DQ<6>
  VSS68  = GND
  DQ7_A  = M_E_CPU1_SA_DQ<7>
  VSS69  = GND
  DQ10_A  = M_E_CPU1_SA_DQ<10>
  VSS70  = GND
  DQ11_A  = M_E_CPU1_SA_DQ<11>
  VSS71  = GND
  \dqs6_a_c||tdqs6_a_c||dqs6_a_t||tdqs6_a_t\  = M_E_CPU1_SA_DQS_DN<6>
  \dqs6_a_t||tdqs6_a_t\  = M_E_CPU1_SA_DQS_DP<6>
  VSS72  = GND
  DQ14_A  = M_E_CPU1_SA_DQ<14>
  VSS73  = GND
  DQ15_A  = M_E_CPU1_SA_DQ<15>
  VSS74  = GND
  DQ18_A  = M_E_CPU1_SA_DQ<18>
  VSS75  = GND
  DQ19_A  = M_E_CPU1_SA_DQ<19>
  VSS76  = GND
  \dqs7_a_c||tdqs7_a_c\  = M_E_CPU1_SA_DQS_DN<7>
  \dqs7_a_t||tdqs7_a_t\  = M_E_CPU1_SA_DQS_DP<7>
  VSS77  = GND
  DQ22_A  = M_E_CPU1_SA_DQ<22>
  VSS78  = GND
  DQ23_A  = M_E_CPU1_SA_DQ<23>
  VSS79  = GND
  DQ26_A  = M_E_CPU1_SA_DQ<26>
  VSS80  = GND
  DQ27_A  = M_E_CPU1_SA_DQ<27>
  VSS81  = GND
  \dqs8_a_c||tdqs8_a_c\  = M_E_CPU1_SA_DQS_DN<8>
  \dqs8_a_t||tdqs8_a_t\  = M_E_CPU1_SA_DQS_DP<8>
  VSS82  = GND
  DQ30_A  = M_E_CPU1_SA_DQ<30>
  VSS83  = GND
  DQ31_A  = M_E_CPU1_SA_DQ<31>
  VSS84  = GND
  CB2_A  = M_E_CPU1_SA_CB<2>
  VSS85  = GND
  CB3_A  = M_E_CPU1_SA_CB<3>
  VSS86  = GND
  \dqs9_a_c||tdqs9_a_c\  = M_E_CPU1_SA_DQS_DN<9>
  \dqs9_a_t||tdqs9_a_t\  = M_E_CPU1_SA_DQS_DP<9>
  VSS87  = GND
  CB6_A  = M_E_CPU1_SA_CB<6>
  VSS88  = GND
  CB7_A  = M_E_CPU1_SA_CB<7>
  VSS89  = GND
  RESET_N  = RST_M_EF_CPU1_FPGA_N
  VSS90  = GND
  CS1_A_N  = M_E_CPU1_SA_CS_N<3>
  VSS91  = GND
  CA1_A  = M_E_CPU1_SA_CA<1>
  VSS92  = GND
  CA3_A  = M_E_CPU1_SA_CA<3>
  VSS93  = GND
  CA5_A  = M_E_CPU1_SA_CA<5>
  VSS94  = GND
  CK_T  = M_E_CPU1_CLK_DP<1>
  CK_C  = M_E_CPU1_CLK_DN<1>
  VSS95  = GND
  RFU4  = TP_CHE_CPU1_DIMM2_FRU_4
  CA1_B  = M_E_CPU1_SB_CA<1>
  VSS96  = GND
  CA3_B  = M_E_CPU1_SB_CA<3>
  VSS97  = GND
  CA5_B  = M_E_CPU1_SB_CA<5>
  VSS98  = GND
  PAR_B  = M_E_CPU1_SB_PAR
  VSS99  = GND
  CS1_B_N  = M_E_CPU1_SB_CS_N<3>
  VSS100  = GND
  RFU5  = TP_CHE_CPU1_DIMM2_FRU_5
  RFU6  = TP_CHE_CPU1_DIMM2_FRU_6
  VSS101  = GND
  CB6_B  = M_E_CPU1_SB_CB<6>
  VSS102  = GND
  CB7_B  = M_E_CPU1_SB_CB<7>
  VSS103  = GND
  DQS4_B_C  = M_E_CPU1_SB_DQS_DN<4>
  DQS4_B_T  = M_E_CPU1_SB_DQS_DP<4>
  VSS104  = GND
  CB2_B  = M_E_CPU1_SB_CB<2>
  VSS105  = GND
  CB3_B  = M_E_CPU1_SB_CB<3>
  VSS106  = GND
  DQ2_B  = M_E_CPU1_SB_DQ<2>
  VSS107  = GND
  DQ3_B  = M_E_CPU1_SB_DQ<3>
  VSS108  = GND
  \dqs5_b_c||tdqs5_b_c\  = M_E_CPU1_SB_DQS_DN<5>
  \dqs5_b_t||tdqs5_b_t\  = M_E_CPU1_SB_DQS_DP<5>
  VSS109  = GND
  DQ6_B  = M_E_CPU1_SB_DQ<6>
  VSS110  = GND
  DQ7_B  = M_E_CPU1_SB_DQ<7>
  VSS111  = GND
  DQ10_B  = M_E_CPU1_SB_DQ<10>
  VSS112  = GND
  DQ11_B  = M_E_CPU1_SB_DQ<11>
  VSS113  = GND
  \dqs6_b_c||tdqs6_b_c\  = M_E_CPU1_SB_DQS_DN<6>
  \dqs6_b_t||tdqs6_b_t\  = M_E_CPU1_SB_DQS_DP<6>
  VSS114  = GND
  DQ14_B  = M_E_CPU1_SB_DQ<14>
  VSS115  = GND
  DQ15_B  = M_E_CPU1_SB_DQ<15>
  VSS116  = GND
  DQ18_B  = M_E_CPU1_SB_DQ<18>
  VSS117  = GND
  DQ19_B  = M_E_CPU1_SB_DQ<19>
  VSS118  = GND
  \dqs7_b_c||tdqs7_b_c\  = M_E_CPU1_SB_DQS_DN<7>
  \dqs7_b_t||tdqs7_b_t\  = M_E_CPU1_SB_DQS_DP<7>
  VSS119  = GND
  DQ22_B  = M_E_CPU1_SB_DQ<22>
  VSS120  = GND
  DQ23_B  = M_E_CPU1_SB_DQ<23>
  VSS121  = GND
  DQ26_B  = M_E_CPU1_SB_DQ<26>
  VSS122  = GND
  DQ27_B  = M_E_CPU1_SB_DQ<27>
  VSS123  = GND
  \dqs8_b_c||tdqs8_b_c\  = M_E_CPU1_SB_DQS_DN<8>
  \dqs8_b_t||tdqs8_b_t\  = M_E_CPU1_SB_DQS_DP<8>
  VSS124  = GND
  DQ30_B  = M_E_CPU1_SB_DQ<30>
  VSS125  = GND
  DQ31_B  = M_E_CPU1_SB_DQ<31>
  VSS126  = GND
  G1  = GND
  G2  = GND
  G3  = GND

(kicad_pcb
	(version 20260206)
	(generator "pcbnew")
	(generator_version "10.0")
	(general
		(thickness 1.6)
		(legacy_teardrops no)
	)
	(paper "A4")
	(title_block
		(title "03242023_DA0F0TMBIJ0_F0T_Motherboard_J_brd_V01_OCP.brd")
		(comment 1 "Grand Teton / footprint 1065 of 6105 (J26), pads 183-228 of 291")
	)
	(layers
		(0 "F.Cu" signal "TOP")
		(4 "In1.Cu" signal "GND")
		(6 "In2.Cu" signal "IN1")
		(8 "In3.Cu" signal "GND1")
		(10 "In4.Cu" signal "IN2")
		(12 "In5.Cu" signal "GND2")
		(14 "In6.Cu" signal "IN3")
		(16 "In7.Cu" signal "GND3")
		(18 "In8.Cu" signal "VCC")
		(20 "In9.Cu" signal "VCC1")
		(22 "In10.Cu" signal "GND4")
		(24 "In11.Cu" signal "IN4")
		(26 "In12.Cu" signal "GND5")
		(28 "In13.Cu" signal "IN5")
		(30 "In14.Cu" signal "GND6")
		(32 "In15.Cu" signal "IN6")
		(34 "In16.Cu" signal "GND7")
		(2 "B.Cu" signal "BOTTOM")
		(9 "F.Adhes" user "F.Adhesive")
		(11 "B.Adhes" user "B.Adhesive")
		(13 "F.Paste" user "Package Geometry/Pastemask Top")
		(15 "B.Paste" user "Package Geometry/Pastemask Bottom")
		(5 "F.SilkS" user "Ref Des/Silkscreen Top")
		(7 "B.SilkS" user "Ref Des/Silkscreen Bottom")
		(1 "F.Mask" user "Board Geometry/Soldermask Top")
		(3 "B.Mask" user "Board Geometry/Soldermask Bottom")
		(17 "Dwgs.User" user "User.Drawings")
		(19 "Cmts.User" user "User.Comments")
		(21 "Eco1.User" user "User.Eco1")
		(23 "Eco2.User" user "User.Eco2")
		(25 "Edge.Cuts" user "Board Geometry/Outline")
		(27 "Margin" user)
		(31 "F.CrtYd" user "Package Geometry/Place Bound Top")
		(29 "B.CrtYd" user "Package Geometry/Place Bound Bottom")
		(35 "F.Fab" user "Ref Des/Assembly Top")
		(33 "B.Fab" user "Ref Des/Assembly Bottom")
	)
	(footprint ""
		(layer "F.Cu")
		(at 160.86328 -258.091686)
		(property "Reference" "J26"
			(at -3.683 -81.702148 0)
			(unlocked yes)
			(layer "F.SilkS")
			(effects
				(font
					(size 0.7874 0.5842)
					(thickness 0.1524)
				)
				(justify left)
			)
		)
		(property "Value" ""
			(at 0 0 0)
			(layer "F.Fab")
			(effects
				(font
					(size 1.27 1.27)
				)
			)
		)
		(duplicate_pad_numbers_are_jumpers no)
		(pad "183" smd rect
			(at 2.050034 -31.025084 270)
			(size 0.519938 1.4986)
			(layers "F.Cu" "F.Mask" "F.Paste")
			(net "M_E_CPU1_SA_DQ<23>")
		)
		(pad "184" smd rect
			(at 2.050034 -30.174946 270)
			(size 0.519938 1.4986)
			(layers "F.Cu" "F.Mask" "F.Paste")
			(net "GND")
		)
		(pad "185" smd rect
			(at 2.050034 -29.325062 270)
			(size 0.519938 1.4986)
			(layers "F.Cu" "F.Mask" "F.Paste")
			(net "M_E_CPU1_SA_DQ<26>")
		)
		(pad "186" smd rect
			(at 2.050034 -28.474924 270)
			(size 0.519938 1.4986)
			(layers "F.Cu" "F.Mask" "F.Paste")
			(net "GND")
		)
		(pad "187" smd rect
			(at 2.050034 -27.62504 270)
			(size 0.519938 1.4986)
			(layers "F.Cu" "F.Mask" "F.Paste")
			(net "M_E_CPU1_SA_DQ<27>")
		)
		(pad "188" smd rect
			(at 2.050034 -26.774902 270)
			(size 0.519938 1.4986)
			(layers "F.Cu" "F.Mask" "F.Paste")
			(net "GND")
		)
		(pad "189" smd rect
			(at 2.050034 -25.925018 270)
			(size 0.519938 1.4986)
			(layers "F.Cu" "F.Mask" "F.Paste")
			(net "M_E_CPU1_SA_DQS_DN<8>")
		)
		(pad "190" smd rect
			(at 2.050034 -25.07488 270)
			(size 0.519938 1.4986)
			(layers "F.Cu" "F.Mask" "F.Paste")
			(net "M_E_CPU1_SA_DQS_DP<8>")
		)
		(pad "191" smd rect
			(at 2.050034 -24.224996 270)
			(size 0.519938 1.4986)
			(layers "F.Cu" "F.Mask" "F.Paste")
			(net "GND")
		)
		(pad "192" smd rect
			(at 2.050034 -23.375112 270)
			(size 0.519938 1.4986)
			(layers "F.Cu" "F.Mask" "F.Paste")
			(net "M_E_CPU1_SA_DQ<30>")
		)
		(pad "193" smd rect
			(at 2.050034 -22.524974 270)
			(size 0.519938 1.4986)
			(layers "F.Cu" "F.Mask" "F.Paste")
			(net "GND")
		)
		(pad "194" smd rect
			(at 2.050034 -21.67509 270)
			(size 0.519938 1.4986)
			(layers "F.Cu" "F.Mask" "F.Paste")
			(net "M_E_CPU1_SA_DQ<31>")
		)
		(pad "195" smd rect
			(at 2.050034 -20.824952 270)
			(size 0.519938 1.4986)
			(layers "F.Cu" "F.Mask" "F.Paste")
			(net "GND")
		)
		(pad "196" smd rect
			(at 2.050034 -19.975068 270)
			(size 0.519938 1.4986)
			(layers "F.Cu" "F.Mask" "F.Paste")
			(net "M_E_CPU1_SA_CB<2>")
		)
		(pad "197" smd rect
			(at 2.050034 -19.12493 270)
			(size 0.519938 1.4986)
			(layers "F.Cu" "F.Mask" "F.Paste")
			(net "GND")
		)
		(pad "198" smd rect
			(at 2.050034 -18.275046 270)
			(size 0.519938 1.4986)
			(layers "F.Cu" "F.Mask" "F.Paste")
			(net "M_E_CPU1_SA_CB<3>")
		)
		(pad "199" smd rect
			(at 2.050034 -17.424908 270)
			(size 0.519938 1.4986)
			(layers "F.Cu" "F.Mask" "F.Paste")
			(net "GND")
		)
		(pad "200" smd rect
			(at 2.050034 -16.575024 270)
			(size 0.519938 1.4986)
			(layers "F.Cu" "F.Mask" "F.Paste")
			(net "M_E_CPU1_SA_DQS_DN<9>")
		)
		(pad "201" smd rect
			(at 2.050034 -15.724886 270)
			(size 0.519938 1.4986)
			(layers "F.Cu" "F.Mask" "F.Paste")
			(net "M_E_CPU1_SA_DQS_DP<9>")
		)
		(pad "202" smd rect
			(at 2.050034 -14.875002 270)
			(size 0.519938 1.4986)
			(layers "F.Cu" "F.Mask" "F.Paste")
			(net "GND")
		)
		(pad "203" smd rect
			(at 2.050034 -14.025118 270)
			(size 0.519938 1.4986)
			(layers "F.Cu" "F.Mask" "F.Paste")
			(net "M_E_CPU1_SA_CB<6>")
		)
		(pad "204" smd rect
			(at 2.050034 -13.17498 270)
			(size 0.519938 1.4986)
			(layers "F.Cu" "F.Mask" "F.Paste")
			(net "GND")
		)
		(pad "205" smd rect
			(at 2.050034 -12.325096 270)
			(size 0.519938 1.4986)
			(layers "F.Cu" "F.Mask" "F.Paste")
			(net "M_E_CPU1_SA_CB<7>")
		)
		(pad "206" smd rect
			(at 2.050034 -11.474958 270)
			(size 0.519938 1.4986)
			(layers "F.Cu" "F.Mask" "F.Paste")
			(net "GND")
		)
		(pad "207" smd rect
			(at 2.050034 -10.625074 270)
			(size 0.519938 1.4986)
			(layers "F.Cu" "F.Mask" "F.Paste")
			(net "RST_M_EF_CPU1_FPGA_N")
		)
		(pad "208" smd rect
			(at 2.050034 -9.774936 270)
			(size 0.519938 1.4986)
			(layers "F.Cu" "F.Mask" "F.Paste")
			(net "GND")
		)
		(pad "209" smd rect
			(at 2.050034 -8.925052 270)
			(size 0.519938 1.4986)
			(layers "F.Cu" "F.Mask" "F.Paste")
			(net "M_E_CPU1_SA_CS_N<3>")
		)
		(pad "210" smd rect
			(at 2.050034 -8.074914 270)
			(size 0.519938 1.4986)
			(layers "F.Cu" "F.Mask" "F.Paste")
			(net "GND")
		)
		(pad "211" smd rect
			(at 2.050034 -7.22503 270)
			(size 0.519938 1.4986)
			(layers "F.Cu" "F.Mask" "F.Paste")
			(net "M_E_CPU1_SA_CA<1>")
		)
		(pad "212" smd rect
			(at 2.050034 -6.374892 270)
			(size 0.519938 1.4986)
			(layers "F.Cu" "F.Mask" "F.Paste")
			(net "GND")
		)
		(pad "213" smd rect
			(at 2.050034 -5.525008 270)
			(size 0.519938 1.4986)
			(layers "F.Cu" "F.Mask" "F.Paste")
			(net "M_E_CPU1_SA_CA<3>")
		)
		(pad "214" smd rect
			(at 2.050034 -4.675124 270)
			(size 0.519938 1.4986)
			(layers "F.Cu" "F.Mask" "F.Paste")
			(net "GND")
		)
		(pad "215" smd rect
			(at 2.050034 -3.824986 270)
			(size 0.519938 1.4986)
			(layers "F.Cu" "F.Mask" "F.Paste")
			(net "M_E_CPU1_SA_CA<5>")
		)
		(pad "216" smd rect
			(at 2.050034 -2.975102 270)
			(size 0.519938 1.4986)
			(layers "F.Cu" "F.Mask" "F.Paste")
			(net "GND")
		)
		(pad "217" smd rect
			(at 2.050034 -2.124964 270)
			(size 0.519938 1.4986)
			(layers "F.Cu" "F.Mask" "F.Paste")
			(net "M_E_CPU1_CLK_DP<1>")
		)
		(pad "218" smd rect
			(at 2.050034 -1.27508 270)
			(size 0.519938 1.4986)
			(layers "F.Cu" "F.Mask" "F.Paste")
			(net "M_E_CPU1_CLK_DN<1>")
		)
		(pad "219" smd rect
			(at 2.050034 -0.424942 270)
			(size 0.519938 1.4986)
			(layers "F.Cu" "F.Mask" "F.Paste")
			(net "GND")
		)
		(pad "220" smd rect
			(at 2.050034 5.525008 270)
			(size 0.519938 1.4986)
			(layers "F.Cu" "F.Mask" "F.Paste")
			(net "TP_CHE_CPU1_DIMM2_FRU_4")
		)
		(pad "221" smd rect
			(at 2.050034 6.374892 270)
			(size 0.519938 1.4986)
			(layers "F.Cu" "F.Mask" "F.Paste")
			(net "M_E_CPU1_SB_CA<1>")
		)
		(pad "222" smd rect
			(at 2.050034 7.22503 270)
			(size 0.519938 1.4986)
			(layers "F.Cu" "F.Mask" "F.Paste")
			(net "GND")
		)
		(pad "223" smd rect
			(at 2.050034 8.074914 270)
			(size 0.519938 1.4986)
			(layers "F.Cu" "F.Mask" "F.Paste")
			(net "M_E_CPU1_SB_CA<3>")
		)
		(pad "224" smd rect
			(at 2.050034 8.925052 270)
			(size 0.519938 1.4986)
			(layers "F.Cu" "F.Mask" "F.Paste")
			(net "GND")
		)
		(pad "225" smd rect
			(at 2.050034 9.774936 270)
			(size 0.519938 1.4986)
			(layers "F.Cu" "F.Mask" "F.Paste")
			(net "M_E_CPU1_SB_CA<5>")
		)
		(pad "226" smd rect
			(at 2.050034 10.625074 270)
			(size 0.519938 1.4986)
			(layers "F.Cu" "F.Mask" "F.Paste")
			(net "GND")
		)
		(pad "227" smd rect
			(at 2.050034 11.474958 270)
			(size 0.519938 1.4986)
			(layers "F.Cu" "F.Mask" "F.Paste")
			(net "M_E_CPU1_SB_PAR")
		)
		(pad "228" smd rect
			(at 2.050034 12.325096 270)
			(size 0.519938 1.4986)
			(layers "F.Cu" "F.Mask" "F.Paste")
			(net "GND")
		)
	)
)
